FILE_TYPE = CONNECTIVITY;
{Allegro Design Entry HDL 17.2-2016 S081 (4005846) 1/11/2022}
"PAGE_NUMBER" = 129;
0"NC";
1"PVCCD_HV_CPU0\g";
2"PVCCD_HV_CPU0\g";
3"PVCCD_HV_CPU0\g";
4"PVCCD_HV_CPU0\g";
5"GND\g";
6"GND\g";
7"GND\g";
8"GND\g";
9"RST_M_GH_CPU0_FPGA_N";
10"RST_M_EF_CPU0_FPGA_N";
11"RST_PLD_CPU0_DRAM_AB_N";
12"RST_M_AB_CPU0_FPGA_N";
13"RST_M_CD_CPU0_FPGA_N";
14"RST_PLD_CPU0_DRAM_GH_N";
15"RST_PLD_CPU0_DRAM_EF_N";
16"RST_PLD_CPU0_DRAM_CD_N";
%"UNIVERSAL_GND"
"1","(-7475,300)","0","logical_power","I100";
;
CDS_LIB"logical_power"
HDL_POWER"GND";
"A"8;
%"Q_CAP"
"1","(-7475,600)","2","pure_quanta","I102";
;
PART_NUMBER"CH5104KEB02"
PACK_TYPE"C0402"
VALUE"1UF"
VOLTAGE"25V"
TOLERANCE"10%"
MATERIAL"EMPTY"
$LOCATION"C621"
CDS_LIB"pure_quanta"
CDS_LOCATION"C621"
$SEC"1"
CDS_SEC"1";
"B"
$PN"2"8;
"A"
$PN"1"14;
%"Q_RES"
"2","(-7350,5150)","0","pure_quanta","I103";
;
PART_NUMBER"CS31002FB08"
WATTAGE"1/16W"
VALUE"10K"
MATERIAL"EMPTY"
TOLERANCE"1%"
PACK_TYPE"0402LF"
$LOCATION"R706"
CDS_LIB"pure_quanta"
CDS_LOCATION"R706"
$SEC"1"
CDS_SEC"1";
"A"
$PN"1"11;
"B"
$PN"2"7;
%"Q_RES"
"2","(-7350,3625)","0","pure_quanta","I106";
;
PART_NUMBER"CS31002FB08"
MATERIAL"EMPTY"
WATTAGE"1/16W"
VALUE"10K"
PACK_TYPE"0402LF"
TOLERANCE"1%"
$LOCATION"R707"
CDS_LIB"pure_quanta"
CDS_LOCATION"R707"
$SEC"1"
CDS_SEC"1";
"A"
$PN"1"16;
"B"
$PN"2"6;
%"Q_RES"
"2","(-7350,2125)","0","pure_quanta","I109";
;
PART_NUMBER"CS31002FB08"
WATTAGE"1/16W"
VALUE"10K"
TOLERANCE"1%"
MATERIAL"EMPTY"
PACK_TYPE"0402LF"
$LOCATION"R708"
CDS_LIB"pure_quanta"
CDS_LOCATION"R708"
$SEC"1"
CDS_SEC"1";
"A"
$PN"1"15;
"B"
$PN"2"5;
%"Q_RES"
"2","(-7350,600)","0","pure_quanta","I112";
;
PART_NUMBER"CS31002FB08"
MATERIAL"EMPTY"
TOLERANCE"1%"
PACK_TYPE"0402LF"
VALUE"10K"
WATTAGE"1/16W"
$LOCATION"R705"
CDS_LIB"pure_quanta"
CDS_LOCATION"R705"
$SEC"1"
CDS_SEC"1";
"A"
$PN"1"14;
"B"
$PN"2"8;
%"Q_RES"
"2","(-2725,5775)","0","pure_quanta","I119";
;
PART_NUMBER"CS21002FB06"
PACK_TYPE"0402LF"
TOLERANCE"1%"
VALUE"1K"
WATTAGE"1/16W"
MATERIAL"CHIP"
$LOCATION"R840"
CDS_LIB"pure_quanta"
$LOCATION"R840"
CDS_LOCATION"R840"
$SEC"1"
CDS_SEC"1";
"A"
$PN"1"4;
"B"
$PN"2"12;
%"UNIVERSAL_POWER"
"1","(-2725,6025)","0","logical_power","I120";
;
HDL_POWER"PVCCD_HV_CPU0"
CDS_LIB"logical_power";
"A"4;
%"Q_RES"
"2","(-2725,4250)","0","pure_quanta","I121";
;
PART_NUMBER"CS21002FB06"
TOLERANCE"1%"
VALUE"1K"
PACK_TYPE"0402LF"
WATTAGE"1/16W"
MATERIAL"CHIP"
$LOCATION"R841"
CDS_LIB"pure_quanta"
$LOCATION"R841"
CDS_LOCATION"R841"
$SEC"1"
CDS_SEC"1";
"A"
$PN"1"3;
"B"
$PN"2"13;
%"UNIVERSAL_POWER"
"1","(-2725,4500)","0","logical_power","I122";
;
HDL_POWER"PVCCD_HV_CPU0"
CDS_LIB"logical_power";
"A"3;
%"Q_RES"
"2","(-2725,2750)","0","pure_quanta","I123";
;
PART_NUMBER"CS21002FB06"
PACK_TYPE"0402LF"
VALUE"1K"
TOLERANCE"1%"
WATTAGE"1/16W"
MATERIAL"CHIP"
$LOCATION"R842"
CDS_LIB"pure_quanta"
$LOCATION"R842"
CDS_LOCATION"R842"
$SEC"1"
CDS_SEC"1";
"A"
$PN"1"2;
"B"
$PN"2"10;
%"UNIVERSAL_POWER"
"1","(-2725,3000)","0","logical_power","I124";
;
HDL_POWER"PVCCD_HV_CPU0"
CDS_LIB"logical_power";
"A"2;
%"Q_RES"
"2","(-2725,1225)","0","pure_quanta","I125";
;
PART_NUMBER"CS21002FB06"
PACK_TYPE"0402LF"
VALUE"1K"
WATTAGE"1/16W"
MATERIAL"CHIP"
TOLERANCE"1%"
$LOCATION"R839"
CDS_LIB"pure_quanta"
$LOCATION"R839"
CDS_LOCATION"R839"
$SEC"1"
CDS_SEC"1";
"A"
$PN"1"1;
"B"
$PN"2"9;
%"UNIVERSAL_POWER"
"1","(-2725,1475)","0","logical_power","I126";
;
HDL_POWER"PVCCD_HV_CPU0"
CDS_LIB"logical_power";
"A"1;
%"Q_RES"
"1","(-4900,5450)","0","pure_quanta","I26";
;
PART_NUMBER"CS00002JB13"
MATERIAL"CHIP"
VALUE"0"
TOLERANCE"5%"
PACK_TYPE"0402LF"
WATTAGE"1/16W"
$LOCATION"R836"
CDS_LIB"pure_quanta"
$LOCATION"R836"
CDS_LOCATION"R836"
$SEC"1"
CDS_SEC"1";
"B"
$PN"2"12;
"A"
$PN"1"11;
%"Q_RES"
"1","(-4900,3925)","0","pure_quanta","I59";
;
PART_NUMBER"CS00002JB13"
WATTAGE"1/16W"
MATERIAL"CHIP"
VALUE"0"
PACK_TYPE"0402LF"
TOLERANCE"5%"
$LOCATION"R837"
CDS_LIB"pure_quanta"
$LOCATION"R837"
CDS_LOCATION"R837"
$SEC"1"
CDS_SEC"1";
"B"
$PN"2"13;
"A"
$PN"1"16;
%"Q_RES"
"1","(-4900,2425)","0","pure_quanta","I76";
;
PART_NUMBER"CS00002JB13"
MATERIAL"CHIP"
TOLERANCE"5%"
VALUE"0"
PACK_TYPE"0402LF"
WATTAGE"1/16W"
$LOCATION"R838"
CDS_LIB"pure_quanta"
$LOCATION"R838"
CDS_LOCATION"R838"
$SEC"1"
CDS_SEC"1";
"B"
$PN"2"10;
"A"
$PN"1"15;
%"Q_RES"
"1","(-4900,900)","0","pure_quanta","I86";
;
PART_NUMBER"CS00002JB13"
PACK_TYPE"0402LF"
TOLERANCE"5%"
VALUE"0"
WATTAGE"1/16W"
MATERIAL"CHIP"
$LOCATION"R835"
CDS_LIB"pure_quanta"
$LOCATION"R835"
CDS_LOCATION"R835"
$SEC"1"
CDS_SEC"1";
"B"
$PN"2"9;
"A"
$PN"1"14;
%"Q_CAP"
"1","(-7475,5150)","2","pure_quanta","I91";
;
PART_NUMBER"CH5104KEB02"
MATERIAL"EMPTY"
VALUE"1UF"
VOLTAGE"25V"
PACK_TYPE"C0402"
TOLERANCE"10%"
$LOCATION"C622"
CDS_LIB"pure_quanta"
CDS_LOCATION"C622"
$SEC"1"
CDS_SEC"1";
"B"
$PN"2"7;
"A"
$PN"1"11;
%"UNIVERSAL_GND"
"1","(-7475,4850)","0","logical_power","I93";
;
CDS_LIB"logical_power"
HDL_POWER"GND";
"A"7;
%"Q_CAP"
"1","(-7475,3625)","2","pure_quanta","I94";
;
PART_NUMBER"CH5104KEB02"
TOLERANCE"10%"
PACK_TYPE"C0402"
VALUE"1UF"
VOLTAGE"25V"
MATERIAL"EMPTY"
$LOCATION"C623"
CDS_LIB"pure_quanta"
CDS_LOCATION"C623"
$SEC"1"
CDS_SEC"1";
"B"
$PN"2"6;
"A"
$PN"1"16;
%"UNIVERSAL_GND"
"1","(-7475,3325)","0","logical_power","I96";
;
CDS_LIB"logical_power"
HDL_POWER"GND";
"A"6;
%"UNIVERSAL_GND"
"1","(-7475,1825)","0","logical_power","I97";
;
CDS_LIB"logical_power"
HDL_POWER"GND";
"A"5;
%"Q_CAP"
"1","(-7475,2125)","2","pure_quanta","I99";
;
PART_NUMBER"CH5104KEB02"
MATERIAL"EMPTY"
PACK_TYPE"C0402"
TOLERANCE"10%"
VOLTAGE"25V"
VALUE"1UF"
$LOCATION"C624"
CDS_LIB"pure_quanta"
CDS_LOCATION"C624"
$SEC"1"
CDS_SEC"1";
"B"
$PN"2"5;
"A"
$PN"1"15;
END.
